# S9S_MB_2U (Grand Teton) — schematic netlist excerpt (pin names and nets, part order shuffled) for the footprints in the layout excerpt that follows; sources: Cadence DE-HDL packaged netlist, KiCad conversion of 03242023_DA0F0TMBIJ0_F0T_Motherboard_J_brd_V01_OCP.brd

PC1202_P1_4  Q_CAP  22UF 16V 20% X6S  pkg C0805  page 290 : A = SW_P12V_PVCCFA_EHV_FIVRA_CPU1_L ; B = GND
R2575  Q_RES  1K 1% CHIP  pkg 0402LF  page 296 : A = P3V3_AUX ; B = PWRGD_PVCCD_HV_CPU1_R
PC514_P1_5  Q_CAP  22UF 16V 20% X6S  pkg C0805  page 287 : A = SW_P12V_PVCCIN_CPU1_FLT ; B = GND

(kicad_pcb
	(version 20260206)
	(generator "pcbnew")
	(generator_version "10.0")
	(general
		(thickness 1.6)
		(legacy_teardrops no)
	)
	(paper "A4")
	(title_block
		(title "03242023_DA0F0TMBIJ0_F0T_Motherboard_J_brd_V01_OCP.brd")
		(comment 1 "Grand Teton / footprints 4663-4665 of 6105")
	)
	(layers
		(0 "F.Cu" signal "TOP")
		(4 "In1.Cu" signal "GND")
		(6 "In2.Cu" signal "IN1")
		(8 "In3.Cu" signal "GND1")
		(10 "In4.Cu" signal "IN2")
		(12 "In5.Cu" signal "GND2")
		(14 "In6.Cu" signal "IN3")
		(16 "In7.Cu" signal "GND3")
		(18 "In8.Cu" signal "VCC")
		(20 "In9.Cu" signal "VCC1")
		(22 "In10.Cu" signal "GND4")
		(24 "In11.Cu" signal "IN4")
		(26 "In12.Cu" signal "GND5")
		(28 "In13.Cu" signal "IN5")
		(30 "In14.Cu" signal "GND6")
		(32 "In15.Cu" signal "IN6")
		(34 "In16.Cu" signal "GND7")
		(2 "B.Cu" signal "BOTTOM")
		(9 "F.Adhes" user "F.Adhesive")
		(11 "B.Adhes" user "B.Adhesive")
		(13 "F.Paste" user "Package Geometry/Pastemask Top")
		(15 "B.Paste" user "Package Geometry/Pastemask Bottom")
		(5 "F.SilkS" user "Ref Des/Silkscreen Top")
		(7 "B.SilkS" user "Ref Des/Silkscreen Bottom")
		(1 "F.Mask" user "Board Geometry/Soldermask Top")
		(3 "B.Mask" user "Board Geometry/Soldermask Bottom")
		(17 "Dwgs.User" user "User.Drawings")
		(19 "Cmts.User" user "User.Comments")
		(21 "Eco1.User" user "User.Eco1")
		(23 "Eco2.User" user "User.Eco2")
		(25 "Edge.Cuts" user "Board Geometry/Outline")
		(27 "Margin" user)
		(31 "F.CrtYd" user "Package Geometry/Place Bound Top")
		(29 "B.CrtYd" user "Package Geometry/Place Bound Bottom")
		(35 "F.Fab" user "Ref Des/Assembly Top")
		(33 "B.Fab" user "Ref Des/Assembly Bottom")
	)
	(footprint ""
		(layer "B.Cu")
		(at 130.860546 -341.218012 -90)
		(property "Reference" "PC514_P1_5"
			(at 0 0 90)
			(layer "B.SilkS")
			(hide yes)
			(effects
				(font
					(size 1.27 1.27)
				)
				(justify mirror)
			)
		)
		(property "Value" ""
			(at 0 0 90)
			(layer "B.Fab")
			(effects
				(font
					(size 1.27 1.27)
				)
				(justify mirror)
			)
		)
		(duplicate_pad_numbers_are_jumpers no)
		(fp_line
			(start -1.524 0.762)
			(end 1.524 0.762)
			(stroke
				(width 0.1524)
				(type default)
			)
			(layer "B.SilkS")
		)
		(fp_line
			(start 1.524 0.762)
			(end 1.524 -0.762)
			(stroke
				(width 0.1524)
				(type default)
			)
			(layer "B.SilkS")
		)
		(fp_line
			(start -1.524 -0.762)
			(end -1.524 0.762)
			(stroke
				(width 0.1524)
				(type default)
			)
			(layer "B.SilkS")
		)
		(fp_line
			(start 1.524 -0.762)
			(end -1.524 -0.762)
			(stroke
				(width 0.1524)
				(type default)
			)
			(layer "B.SilkS")
		)
		(fp_line
			(start -1.1049 0.724916)
			(end -1.1049 -0.724916)
			(stroke
				(width 0.1)
				(type default)
			)
			(layer "B.Fab")
		)
		(fp_line
			(start 1.1049 0.724916)
			(end -1.1049 0.724916)
			(stroke
				(width 0.1)
				(type default)
			)
			(layer "B.Fab")
		)
		(fp_line
			(start -1.1049 -0.724916)
			(end 1.1049 -0.724916)
			(stroke
				(width 0.1)
				(type default)
			)
			(layer "B.Fab")
		)
		(fp_line
			(start 1.1049 -0.724916)
			(end 1.1049 0.724916)
			(stroke
				(width 0.1)
				(type default)
			)
			(layer "B.Fab")
		)
		(pad "1" smd rect
			(at 0.889 0 270)
			(size 1.016 1.27)
			(layers "B.Cu" "B.Mask" "B.Paste")
			(net "SW_P12V_PVCCIN_CPU1_FLT")
		)
		(pad "2" smd rect
			(at -0.889 0 270)
			(size 1.016 1.27)
			(layers "B.Cu" "B.Mask" "B.Paste")
			(net "GND")
		)
	)
	(footprint ""
		(layer "B.Cu")
		(at 42.686732 -353.567492 90)
		(property "Reference" "PC1202_P1_4"
			(at 0 0 90)
			(layer "B.SilkS")
			(hide yes)
			(effects
				(font
					(size 1.27 1.27)
				)
				(justify mirror)
			)
		)
		(property "Value" ""
			(at 0 0 90)
			(layer "B.Fab")
			(effects
				(font
					(size 1.27 1.27)
				)
				(justify mirror)
			)
		)
		(duplicate_pad_numbers_are_jumpers no)
		(fp_line
			(start 1.524 -0.762)
			(end -1.524 -0.762)
			(stroke
				(width 0.1524)
				(type default)
			)
			(layer "B.SilkS")
		)
		(fp_line
			(start -1.524 -0.762)
			(end -1.524 0.762)
			(stroke
				(width 0.1524)
				(type default)
			)
			(layer "B.SilkS")
		)
		(fp_line
			(start 1.524 0.762)
			(end 1.524 -0.762)
			(stroke
				(width 0.1524)
				(type default)
			)
			(layer "B.SilkS")
		)
		(fp_line
			(start -1.524 0.762)
			(end 1.524 0.762)
			(stroke
				(width 0.1524)
				(type default)
			)
			(layer "B.SilkS")
		)
		(fp_line
			(start 1.1049 -0.724916)
			(end 1.1049 0.724916)
			(stroke
				(width 0.1)
				(type default)
			)
			(layer "B.Fab")
		)
		(fp_line
			(start -1.1049 -0.724916)
			(end 1.1049 -0.724916)
			(stroke
				(width 0.1)
				(type default)
			)
			(layer "B.Fab")
		)
		(fp_line
			(start 1.1049 0.724916)
			(end -1.1049 0.724916)
			(stroke
				(width 0.1)
				(type default)
			)
			(layer "B.Fab")
		)
		(fp_line
			(start -1.1049 0.724916)
			(end -1.1049 -0.724916)
			(stroke
				(width 0.1)
				(type default)
			)
			(layer "B.Fab")
		)
		(pad "1" smd rect
			(at 0.889 0 90)
			(size 1.016 1.27)
			(layers "B.Cu" "B.Mask" "B.Paste")
			(net "SW_P12V_PVCCFA_EHV_FIVRA_CPU1_L")
		)
		(pad "2" smd rect
			(at -0.889 0 90)
			(size 1.016 1.27)
			(layers "B.Cu" "B.Mask" "B.Paste")
			(net "GND")
		)
	)
	(footprint ""
		(layer "B.Cu")
		(at 22.48916 -169.659808 180)
		(property "Reference" "R2575"
			(at 0 0 0)
			(layer "B.SilkS")
			(hide yes)
			(effects
				(font
					(size 1.27 1.27)
				)
				(justify mirror)
			)
		)
		(property "Value" ""
			(at 0 0 0)
			(layer "B.Fab")
			(effects
				(font
					(size 1.27 1.27)
				)
				(justify mirror)
			)
		)
		(duplicate_pad_numbers_are_jumpers no)
		(fp_line
			(start 0.7874 0.4064)
			(end 0.7874 -0.4064)
			(stroke
				(width 0.1524)
				(type default)
			)
			(layer "B.SilkS")
		)
		(fp_line
			(start 0.7874 -0.4064)
			(end -0.7874 -0.4064)
			(stroke
				(width 0.1524)
				(type default)
			)
			(layer "B.SilkS")
		)
		(fp_line
			(start -0.7874 0.4064)
			(end 0.7874 0.4064)
			(stroke
				(width 0.1524)
				(type default)
			)
			(layer "B.SilkS")
		)
		(fp_line
			(start -0.7874 -0.4064)
			(end -0.7874 0.4064)
			(stroke
				(width 0.1524)
				(type default)
			)
			(layer "B.SilkS")
		)
		(fp_line
			(start 0.67945 0.3048)
			(end 0.67945 -0.305054)
			(stroke
				(width 0.1)
				(type default)
			)
			(layer "B.Fab")
		)
		(fp_line
			(start 0.67945 -0.305054)
			(end 0.12065 -0.305054)
			(stroke
				(width 0.1)
				(type default)
			)
			(layer "B.Fab")
		)
		(fp_line
			(start 0.12065 0.3048)
			(end 0.67945 0.3048)
			(stroke
				(width 0.1)
				(type default)
			)
			(layer "B.Fab")
		)
		(fp_line
			(start 0.12065 0.2794)
			(end 0.12065 0.3048)
			(stroke
				(width 0.1)
				(type default)
			)
			(layer "B.Fab")
		)
		(fp_line
			(start 0.12065 -0.2794)
			(end -0.12065 -0.2794)
			(stroke
				(width 0.1)
				(type default)
			)
			(layer "B.Fab")
		)
		(fp_line
			(start 0.12065 -0.305054)
			(end 0.12065 -0.2794)
			(stroke
				(width 0.1)
				(type default)
			)
			(layer "B.Fab")
		)
		(fp_line
			(start -0.120396 0.3048)
			(end -0.120396 0.2794)
			(stroke
				(width 0.1)
				(type default)
			)
			(layer "B.Fab")
		)
		(fp_line
			(start -0.120396 0.2794)
			(end 0.12065 0.2794)
			(stroke
				(width 0.1)
				(type default)
			)
			(layer "B.Fab")
		)
		(fp_line
			(start -0.12065 -0.2794)
			(end -0.12065 -0.3048)
			(stroke
				(width 0.1)
				(type default)
			)
			(layer "B.Fab")
		)
		(fp_line
			(start -0.12065 -0.3048)
			(end -0.67945 -0.3048)
			(stroke
				(width 0.1)
				(type default)
			)
			(layer "B.Fab")
		)
		(fp_line
			(start -0.67945 0.3048)
			(end -0.120396 0.3048)
			(stroke
				(width 0.1)
				(type default)
			)
			(layer "B.Fab")
		)
		(fp_line
			(start -0.67945 -0.3048)
			(end -0.67945 0.3048)
			(stroke
				(width 0.1)
				(type default)
			)
			(layer "B.Fab")
		)
		(pad "1" smd circle
			(at 0.40005 0)
			(size 0 0)
			(layers "B.Cu" "B.Mask" "B.Paste")
			(net "P3V3_AUX")
		)
		(pad "2" smd circle
			(at -0.40005 0)
			(size 0 0)
			(layers "B.Cu" "B.Mask" "B.Paste")
			(net "PWRGD_PVCCD_HV_CPU1_R")
		)
	)
)
